FILE_TYPE = MULTI_PHYS_TABLE;

PART 'PCA9617ADP'

{========================================================================================}
:VALUE        | PART_TYPE | MATERIAL | PART_NUMBER       = STANDARD    | LIFECYCLE      | PART_NUMBER       | JEDEC_TYPE   | DESCRIPTION                            | MANUFTR | MANUF_PN     | RD_CMPLS_LVL | CMPLS_LVL | FROM_PJ    | CLASS | DIP_SMD | DATA               | EE_CHECK_LIST | FP_ECN           | PSL | CREATOR | STATUS | CREATEDAY  ;
{========================================================================================}
 'PCA9617ADP' | 'SMLF'    | 'IC'     | 'AL009617K02'(!)  = ''          | ''             | 'AL009617K02'     |'TSSOP8_3XB'| 'IC OTHER(8P) PCA9617ADP(TSSOP)'       | 'NXP'   | 'PCA9617ADP' | 'EP(V1)'     | ''        | 'S1U-OWEN' | 'IC'  | ''      | 'NXP_PCA9617A.pdf' | ''            | ''               | ''  | ''      | ''     | '20140410'
 'PCA9617ADP' | 'SMLF'    | 'EMPTY'  | 'AL009617K02'(!)  = ''          | ''             | 'AL009617K02'     |'TSSOP8_3XB'| 'IC OTHER(8P) PCA9617ADP(TSSOP)'       | 'NXP'   | 'PCA9617ADP' | 'EP(V1)'     | ''        | 'S1U-OWEN' | 'IC'  | ''      | 'NXP_PCA9617A.pdf' | ''            | ''               | ''  | ''      | ''     | '20140410'
 'PCA9617ADP' | 'SMLF'    | 'IC'     | 'AL009617K02SEL1'(!) = ''               | ''               | 'AL009617K02SEL1' |'TSSOP8_3XB'| 'IC OTHER(8P) PCA9617ADP(TSSOP)SELASN' | 'NXP'   | 'PCA9617ADP' | 'EP(V1)'     | 'EP(V1)'  | 'S1U-OWEN' | 'IC'  | ''      | 'NXP_PCA9617A.pdf' | ''            | 'SEL_15QPN.xlsx' | ''  | ''      | ''     | '20230719'
 'PCA9617ADP' | 'SMLF'    | 'EMPTY'  | 'AL009617K02SEL1'(!) = ''               | ''               | 'AL009617K02SEL1' |'TSSOP8_3XB'| 'IC OTHER(8P) PCA9617ADP(TSSOP)SELASN' | 'NXP'   | 'PCA9617ADP' | 'EP(V1)'     | 'EP(V1)'  | 'S1U-OWEN' | 'IC'  | ''      | 'NXP_PCA9617A.pdf' | ''            | 'SEL_15QPN.xlsx' | ''  | ''      | ''     | '20230719'

END_PART

END.

